(kicad_pcb
	(version 20241229)
	(generator "pcbnew")
	(generator_version "9.0")
	(general
		(thickness 1.294)
		(legacy_teardrops no)
	)
	(paper "A3")
	(title_block
		(title "Kintex 410T devboard")
		(date "2024-04-03")
		(rev "1.1.2")
		(comment 9 "footprints 597-602 of 975")
	)
	(layers
		(0 "F.Cu" mixed)
		(4 "In1.Cu" power)
		(6 "In2.Cu" power)
		(8 "In3.Cu" mixed)
		(10 "In4.Cu" power)
		(12 "In5.Cu" mixed)
		(14 "In6.Cu" power)
		(16 "In7.Cu" mixed)
		(18 "In8.Cu" power)
		(2 "B.Cu" mixed)
		(9 "F.Adhes" user "F.Adhesive")
		(11 "B.Adhes" user "B.Adhesive")
		(13 "F.Paste" user)
		(15 "B.Paste" user)
		(5 "F.SilkS" user "F.Silkscreen")
		(7 "B.SilkS" user "B.Silkscreen")
		(1 "F.Mask" user)
		(3 "B.Mask" user)
		(17 "Dwgs.User" user "User.Drawings")
		(19 "Cmts.User" user "User.Comments")
		(21 "Eco1.User" user "User.Eco1")
		(23 "Eco2.User" user "User.Eco2")
		(25 "Edge.Cuts" user)
		(27 "Margin" user)
		(31 "F.CrtYd" user "F.Courtyard")
		(29 "B.CrtYd" user "B.Courtyard")
		(35 "F.Fab" user)
		(33 "B.Fab" user)
	)
	(footprint "antmicro-footprints:R_0402_1005Metric"
		(layer "B.Cu")
		(at 258.4 93.4 -90)
		(descr "Resistor SMD 0402")
		(tags "resistor SMD 0402")
		(property "Reference" "R357"
			(at -1.45 -1.275 90)
			(layer "B.SilkS")
			(effects
				(font
					(size 0.7 0.7)
					(thickness 0.15)
				)
				(justify left bottom mirror)
			)
		)
		(property "Value" "R_100k_0402"
			(at 0 -1.4 90)
			(layer "B.Fab")
			(effects
				(font
					(size 0.7 0.7)
					(thickness 0.15)
				)
				(justify left bottom mirror)
			)
		)
		(property "Description" "SMD Chip Resistor, 100 kohm, ± 1%, 62.5 mW, 0402 [1005 Metric], Thick Film, General Purpose"
			(at 0 0 270)
			(layer "F.Fab")
			(hide yes)
			(effects
				(font
					(size 1.27 1.27)
					(thickness 0.15)
				)
			)
		)
		(property "Author" "Antmicro"
			(at 165 351.8 0)
			(layer "B.Fab")
			(hide yes)
			(effects
				(font
					(size 1 1)
					(thickness 0.15)
				)
				(justify mirror)
			)
		)
		(property "License" "Apache-2.0"
			(at 165 351.8 0)
			(layer "B.Fab")
			(hide yes)
			(effects
				(font
					(size 1 1)
					(thickness 0.15)
				)
				(justify mirror)
			)
		)
		(property "MPN" "CR0402-FX-1003GLF"
			(at 165 351.8 0)
			(layer "B.Fab")
			(hide yes)
			(effects
				(font
					(size 1 1)
					(thickness 0.15)
				)
				(justify mirror)
			)
		)
		(property "Manufacturer" "Bourns"
			(at 165 351.8 0)
			(layer "B.Fab")
			(hide yes)
			(effects
				(font
					(size 1 1)
					(thickness 0.15)
				)
				(justify mirror)
			)
		)
		(property "Tolerance" "1%"
			(at 165 351.8 0)
			(layer "B.Fab")
			(hide yes)
			(effects
				(font
					(size 1 1)
					(thickness 0.15)
				)
				(justify mirror)
			)
		)
		(property "Val" "100k"
			(at 165 351.8 0)
			(layer "B.Fab")
			(hide yes)
			(effects
				(font
					(size 1 1)
					(thickness 0.15)
				)
				(justify mirror)
			)
		)
		(sheetname "User GPIO + LED + button + DIP switch")
		(sheetfile "user-gpio.kicad_sch")
		(attr smd)
		(fp_rect
			(start -0.925 0.47)
			(end 0.925 -0.47)
			(stroke
				(width 0.05)
				(type default)
			)
			(fill no)
			(layer "B.CrtYd")
		)
		(fp_rect
			(start -0.5 0.25)
			(end 0.5 -0.25)
			(stroke
				(width 0.15)
				(type solid)
			)
			(fill no)
			(layer "B.Fab")
		)
		(pad "1" smd roundrect
			(at -0.48 0 270)
			(size 0.59 0.64)
			(layers "B.Cu" "B.Mask" "B.Paste")
			(roundrect_rratio 0.25)
			(net 1303 "/USER_IO.LED_GREEN4")
			(pintype "passive")
		)
		(pad "2" smd roundrect
			(at 0.48 0 270)
			(size 0.59 0.64)
			(layers "B.Cu" "B.Mask" "B.Paste")
			(roundrect_rratio 0.25)
			(net 1 "GND")
			(pintype "passive")
		)
	)
	(footprint "antmicro-footprints:C_0201"
		(layer "B.Cu")
		(at 198.5 128)
		(descr "Capacitor SMD 0201")
		(tags "capacitor SMD 0201")
		(property "Reference" "C388"
			(at 23.5 -28.825 0)
			(layer "B.SilkS")
			(effects
				(font
					(size 0.7 0.7)
					(thickness 0.15)
				)
				(justify right bottom mirror)
			)
		)
		(property "Value" "C_100n_0201"
			(at 0 -1.4 0)
			(layer "B.Fab")
			(effects
				(font
					(size 0.7 0.7)
					(thickness 0.15)
				)
				(justify right bottom mirror)
			)
		)
		(property "Description" "SMD Multilayer Ceramic Capacitor, 0.1 µF, 6.3 V, 0201 [0603 Metric], ± 10%, X6S, CC Series"
			(at 0 0 0)
			(layer "F.Fab")
			(hide yes)
			(effects
				(font
					(size 1.27 1.27)
					(thickness 0.15)
				)
			)
		)
		(property "Author" "Antmicro"
			(at 0 0 0)
			(layer "B.Fab")
			(hide yes)
			(effects
				(font
					(size 1 1)
					(thickness 0.15)
				)
				(justify mirror)
			)
		)
		(property "Dielectric" ""
			(at 0 0 0)
			(layer "B.Fab")
			(hide yes)
			(effects
				(font
					(size 1 1)
					(thickness 0.15)
				)
				(justify mirror)
			)
		)
		(property "License" "Apache-2.0"
			(at 0 0 0)
			(layer "B.Fab")
			(hide yes)
			(effects
				(font
					(size 1 1)
					(thickness 0.15)
				)
				(justify mirror)
			)
		)
		(property "MPN" "CC0201KRX6S5BB104"
			(at 0 0 0)
			(layer "B.Fab")
			(hide yes)
			(effects
				(font
					(size 1 1)
					(thickness 0.15)
				)
				(justify mirror)
			)
		)
		(property "Manufacturer" "YAGEO"
			(at 0 0 0)
			(layer "B.Fab")
			(hide yes)
			(effects
				(font
					(size 1 1)
					(thickness 0.15)
				)
				(justify mirror)
			)
		)
		(property "Val" "100n"
			(at 0 0 0)
			(layer "B.Fab")
			(hide yes)
			(effects
				(font
					(size 1 1)
					(thickness 0.15)
				)
				(justify mirror)
			)
		)
		(property "Voltage" ""
			(at 0 0 0)
			(layer "B.Fab")
			(hide yes)
			(effects
				(font
					(size 1 1)
					(thickness 0.15)
				)
				(justify mirror)
			)
		)
		(sheetname "FPGA supply")
		(sheetfile "fpga-supply.kicad_sch")
		(attr smd)
		(fp_rect
			(start -0.7 0.35)
			(end 0.7 -0.35)
			(stroke
				(width 0.05)
				(type default)
			)
			(fill no)
			(layer "B.CrtYd")
		)
		(fp_rect
			(start 0.3 -0.15)
			(end -0.301 0.149)
			(stroke
				(width 0.15)
				(type solid)
			)
			(fill no)
			(layer "B.Fab")
		)
		(pad "" smd roundrect
			(at -0.349 0.002)
			(size 0.318 0.36)
			(layers "B.Paste")
			(roundrect_rratio 0.25)
		)
		(pad "" smd roundrect
			(at 0.341 0.002)
			(size 0.318 0.36)
			(layers "B.Paste")
			(roundrect_rratio 0.25)
		)
		(pad "1" smd roundrect
			(at -0.321 0.002)
			(size 0.46 0.4)
			(layers "B.Cu" "B.Mask")
			(roundrect_rratio 0.25)
			(net 1 "GND")
			(pintype "passive")
		)
		(pad "2" smd roundrect
			(at 0.32 0.002)
			(size 0.46 0.4)
			(layers "B.Cu" "B.Mask")
			(roundrect_rratio 0.25)
			(net 622 "+1V85_ADC")
			(pintype "passive")
		)
	)
	(footprint "antmicro-footprints:F_1206_3216Metric"
		(layer "B.Cu")
		(at 259.251 181.75)
		(property "Reference" "F1"
			(at 0.624 2.075 180)
			(layer "B.SilkS")
			(effects
				(font
					(size 0.7 0.7)
					(thickness 0.15)
				)
				(justify left bottom mirror)
			)
		)
		(property "Value" "F_10A_1206"
			(at 0 -2 180)
			(layer "B.Fab")
			(effects
				(font
					(size 0.7 0.7)
					(thickness 0.15)
				)
				(justify left bottom mirror)
			)
		)
		(property "Description" "Fuse, Surface Mount, 10 A, Slow Blow, 32 VAC, 63 VDC, 1206 (3216 Metric), UST 1206"
			(at 0 0 0)
			(layer "F.Fab")
			(hide yes)
			(effects
				(font
					(size 1.27 1.27)
					(thickness 0.15)
				)
			)
		)
		(property "Author" "Antmicro"
			(at 0 0 0)
			(layer "B.Fab")
			(hide yes)
			(effects
				(font
					(size 1 1)
					(thickness 0.15)
				)
				(justify mirror)
			)
		)
		(property "License" "Apache-2.0"
			(at 0 0 0)
			(layer "B.Fab")
			(hide yes)
			(effects
				(font
					(size 1 1)
					(thickness 0.15)
				)
				(justify mirror)
			)
		)
		(property "MPN" "3413.0328.22"
			(at 0 0 0)
			(layer "B.Fab")
			(hide yes)
			(effects
				(font
					(size 1 1)
					(thickness 0.15)
				)
				(justify mirror)
			)
		)
		(property "Manufacturer" "Schurter"
			(at 0 0 0)
			(layer "B.Fab")
			(hide yes)
			(effects
				(font
					(size 1 1)
					(thickness 0.15)
				)
				(justify mirror)
			)
		)
		(sheetname "Power supply")
		(sheetfile "power-supply.kicad_sch")
		(attr smd)
		(fp_line
			(start 0.8 -0.901)
			(end -0.8 -0.901)
			(stroke
				(width 0.15)
				(type solid)
			)
			(layer "B.SilkS")
		)
		(fp_line
			(start 0.8 0.899)
			(end -0.8 0.899)
			(stroke
				(width 0.15)
				(type solid)
			)
			(layer "B.SilkS")
		)
		(fp_rect
			(start -2.325 1.15)
			(end 2.325 -1.15)
			(stroke
				(width 0.05)
				(type default)
			)
			(fill no)
			(layer "B.CrtYd")
		)
		(fp_line
			(start -1.677 -0.792)
			(end -1.677 0.861)
			(stroke
				(width 0.15)
				(type solid)
			)
			(layer "B.Fab")
		)
		(fp_line
			(start -1.677 0.861)
			(end 1.624 0.861)
			(stroke
				(width 0.15)
				(type solid)
			)
			(layer "B.Fab")
		)
		(fp_line
			(start 1.624 -0.792)
			(end -1.677 -0.792)
			(stroke
				(width 0.15)
				(type solid)
			)
			(layer "B.Fab")
		)
		(fp_line
			(start 1.624 0.861)
			(end 1.624 -0.792)
			(stroke
				(width 0.15)
				(type solid)
			)
			(layer "B.Fab")
		)
		(pad "1" smd roundrect
			(at -1.5 -0.001)
			(size 1.15 1.8)
			(layers "B.Cu" "B.Mask" "B.Paste")
			(roundrect_rratio 0.25)
			(net 1192 "Net-(F1-Pad1)")
			(pintype "passive")
		)
		(pad "2" smd roundrect
			(at 1.5 -0.001)
			(size 1.15 1.8)
			(layers "B.Cu" "B.Mask" "B.Paste")
			(roundrect_rratio 0.25)
			(net 4 "/Power supply/DC_IN")
			(pintype "passive")
		)
	)
	(footprint "antmicro-footprints:R_0402_1005Metric"
		(layer "B.Cu")
		(at 253.501 161.6 90)
		(descr "Resistor SMD 0402")
		(tags "resistor SMD 0402")
		(property "Reference" "R249"
			(at 1.35 5.874 270)
			(layer "B.SilkS")
			(effects
				(font
					(size 0.7 0.7)
					(thickness 0.15)
				)
				(justify left bottom mirror)
			)
		)
		(property "Value" "R_49R9_0402"
			(at 0 -1.4 270)
			(layer "B.Fab")
			(effects
				(font
					(size 0.7 0.7)
					(thickness 0.15)
				)
				(justify left bottom mirror)
			)
		)
		(property "Description" "SMD Chip Resistor, 49.9 ohm, ± 1%, 62.5 mW, 0402 [1005 Metric], Thick Film, General Purpose"
			(at 0 0 90)
			(layer "F.Fab")
			(hide yes)
			(effects
				(font
					(size 1.27 1.27)
					(thickness 0.15)
				)
			)
		)
		(property "Author" "Antmicro"
			(at 415.101 -91.901 0)
			(layer "B.Fab")
			(hide yes)
			(effects
				(font
					(size 1 1)
					(thickness 0.15)
				)
				(justify mirror)
			)
		)
		(property "License" "Apache-2.0"
			(at 415.101 -91.901 0)
			(layer "B.Fab")
			(hide yes)
			(effects
				(font
					(size 1 1)
					(thickness 0.15)
				)
				(justify mirror)
			)
		)
		(property "MPN" "CR0402-FX-49R9GLF"
			(at 415.101 -91.901 0)
			(layer "B.Fab")
			(hide yes)
			(effects
				(font
					(size 1 1)
					(thickness 0.15)
				)
				(justify mirror)
			)
		)
		(property "Manufacturer" "Bourns"
			(at 415.101 -91.901 0)
			(layer "B.Fab")
			(hide yes)
			(effects
				(font
					(size 1 1)
					(thickness 0.15)
				)
				(justify mirror)
			)
		)
		(property "Tolerance" "1%"
			(at 415.101 -91.901 0)
			(layer "B.Fab")
			(hide yes)
			(effects
				(font
					(size 1 1)
					(thickness 0.15)
				)
				(justify mirror)
			)
		)
		(property "Val" "49R9"
			(at 415.101 -91.901 0)
			(layer "B.Fab")
			(hide yes)
			(effects
				(font
					(size 1 1)
					(thickness 0.15)
				)
				(justify mirror)
			)
		)
		(sheetname "HDMI + Ethernet")
		(sheetfile "hdmi-ethernet.kicad_sch")
		(attr smd)
		(fp_rect
			(start -0.925 0.47)
			(end 0.925 -0.47)
			(stroke
				(width 0.05)
				(type default)
			)
			(fill no)
			(layer "B.CrtYd")
		)
		(fp_rect
			(start -0.5 0.25)
			(end 0.5 -0.25)
			(stroke
				(width 0.15)
				(type solid)
			)
			(fill no)
			(layer "B.Fab")
		)
		(pad "1" smd roundrect
			(at -0.48 0 90)
			(size 0.59 0.64)
			(layers "B.Cu" "B.Mask" "B.Paste")
			(roundrect_rratio 0.25)
			(net 726 "/HDMI + Ethernet/ETH2_P")
			(pintype "passive")
		)
		(pad "2" smd roundrect
			(at 0.48 0 90)
			(size 0.59 0.64)
			(layers "B.Cu" "B.Mask" "B.Paste")
			(roundrect_rratio 0.25)
			(net 721 "/HDMI + Ethernet/ETH_3V3")
			(pintype "passive")
		)
	)
	(footprint "antmicro-footprints:C_0402_1005Metric"
		(layer "B.Cu")
		(at 211.5 120 90)
		(descr "Capacitor SMD 0402")
		(tags "capacitor SMD 0402")
		(property "Reference" "C33"
			(at 1.1 1.25 270)
			(layer "B.SilkS")
			(effects
				(font
					(size 0.7 0.7)
					(thickness 0.15)
				)
				(justify left bottom mirror)
			)
		)
		(property "Value" "C_100n_0402"
			(at 0 -1.169 270)
			(layer "B.Fab")
			(effects
				(font
					(size 0.7 0.7)
					(thickness 0.15)
				)
				(justify left bottom mirror)
			)
		)
		(property "Description" "SMD Multilayer Ceramic Capacitor, 0.1 µF, 50 V, 0402 [1005 Metric], ± 10%, X5R, GRM Series"
			(at 0 0 90)
			(layer "F.Fab")
			(hide yes)
			(effects
				(font
					(size 1.27 1.27)
					(thickness 0.15)
				)
			)
		)
		(property "Author" "Antmicro"
			(at 331.5 -91.5 0)
			(layer "B.Fab")
			(hide yes)
			(effects
				(font
					(size 1 1)
					(thickness 0.15)
				)
				(justify mirror)
			)
		)
		(property "Dielectric" "X5R"
			(at 331.5 -91.5 0)
			(layer "B.Fab")
			(hide yes)
			(effects
				(font
					(size 1 1)
					(thickness 0.15)
				)
				(justify mirror)
			)
		)
		(property "License" "Apache-2.0"
			(at 331.5 -91.5 0)
			(layer "B.Fab")
			(hide yes)
			(effects
				(font
					(size 1 1)
					(thickness 0.15)
				)
				(justify mirror)
			)
		)
		(property "MPN" "GRM155R61H104KE14D"
			(at 331.5 -91.5 0)
			(layer "B.Fab")
			(hide yes)
			(effects
				(font
					(size 1 1)
					(thickness 0.15)
				)
				(justify mirror)
			)
		)
		(property "Manufacturer" "Murata"
			(at 331.5 -91.5 0)
			(layer "B.Fab")
			(hide yes)
			(effects
				(font
					(size 1 1)
					(thickness 0.15)
				)
				(justify mirror)
			)
		)
		(property "Val" "100n"
			(at 331.5 -91.5 0)
			(layer "B.Fab")
			(hide yes)
			(effects
				(font
					(size 1 1)
					(thickness 0.15)
				)
				(justify mirror)
			)
		)
		(property "Voltage" "50V"
			(at 331.5 -91.5 0)
			(layer "B.Fab")
			(hide yes)
			(effects
				(font
					(size 1 1)
					(thickness 0.15)
				)
				(justify mirror)
			)
		)
		(sheetname "FPGA Bank 16 & 17")
		(sheetfile "fpga-bank-16-17.kicad_sch")
		(attr smd)
		(fp_rect
			(start -0.925 0.47)
			(end 0.925 -0.47)
			(stroke
				(width 0.05)
				(type default)
			)
			(fill no)
			(layer "B.CrtYd")
		)
		(fp_line
			(start 0.504 -0.248)
			(end -0.494 -0.248)
			(stroke
				(width 0.15)
				(type solid)
			)
			(layer "B.Fab")
		)
		(fp_line
			(start -0.494 -0.248)
			(end -0.494 0.25)
			(stroke
				(width 0.15)
				(type solid)
			)
			(layer "B.Fab")
		)
		(fp_line
			(start 0.504 0.25)
			(end 0.504 -0.248)
			(stroke
				(width 0.15)
				(type solid)
			)
			(layer "B.Fab")
		)
		(fp_line
			(start -0.494 0.25)
			(end 0.504 0.25)
			(stroke
				(width 0.15)
				(type solid)
			)
			(layer "B.Fab")
		)
		(pad "1" smd roundrect
			(at -0.48 0 90)
			(size 0.59 0.64)
			(layers "B.Cu" "B.Mask" "B.Paste")
			(roundrect_rratio 0.25)
			(net 1 "GND")
			(pintype "passive")
		)
		(pad "2" smd roundrect
			(at 0.48 0 90)
			(size 0.59 0.64)
			(layers "B.Cu" "B.Mask" "B.Paste")
			(roundrect_rratio 0.25)
			(net 3 "VCC_USR_B")
			(pintype "passive")
		)
	)
	(footprint "antmicro-footprints:R_0402_1005Metric"
		(layer "B.Cu")
		(at 202.101 74.233 90)
		(descr "Resistor SMD 0402")
		(tags "resistor SMD 0402")
		(property "Reference" "R4"
			(at -0.742 0.374 270)
			(layer "B.SilkS")
			(effects
				(font
					(size 0.7 0.7)
					(thickness 0.15)
				)
				(justify left bottom mirror)
			)
		)
		(property "Value" "R_10k_0402"
			(at 0 -1.4 270)
			(layer "B.Fab")
			(effects
				(font
					(size 0.7 0.7)
					(thickness 0.15)
				)
				(justify left bottom mirror)
			)
		)
		(property "Description" "SMD Chip Resistor, 10 kohm, ± 1%, 62.5 mW, 0402 [1005 Metric], Thick Film, General Purpose"
			(at 0 0 90)
			(layer "F.Fab")
			(hide yes)
			(effects
				(font
					(size 1.27 1.27)
					(thickness 0.15)
				)
			)
		)
		(property "Author" "Antmicro"
			(at 276.334 -127.868 0)
			(layer "B.Fab")
			(hide yes)
			(effects
				(font
					(size 1 1)
					(thickness 0.15)
				)
				(justify mirror)
			)
		)
		(property "DNP" "DNP"
			(at 276.334 -127.868 0)
			(layer "B.Fab")
			(hide yes)
			(effects
				(font
					(size 1 1)
					(thickness 0.15)
				)
				(justify mirror)
			)
		)
		(property "License" "Apache-2.0"
			(at 276.334 -127.868 0)
			(layer "B.Fab")
			(hide yes)
			(effects
				(font
					(size 1 1)
					(thickness 0.15)
				)
				(justify mirror)
			)
		)
		(property "MPN" "CR0402-FX-1002GLF"
			(at 276.334 -127.868 0)
			(layer "B.Fab")
			(hide yes)
			(effects
				(font
					(size 1 1)
					(thickness 0.15)
				)
				(justify mirror)
			)
		)
		(property "Manufacturer" "Bourns"
			(at 276.334 -127.868 0)
			(layer "B.Fab")
			(hide yes)
			(effects
				(font
					(size 1 1)
					(thickness 0.15)
				)
				(justify mirror)
			)
		)
		(property "Tolerance" "1%"
			(at 276.334 -127.868 0)
			(layer "B.Fab")
			(hide yes)
			(effects
				(font
					(size 1 1)
					(thickness 0.15)
				)
				(justify mirror)
			)
		)
		(property "Val" "10k"
			(at 276.334 -127.868 0)
			(layer "B.Fab")
			(hide yes)
			(effects
				(font
					(size 1 1)
					(thickness 0.15)
				)
				(justify mirror)
			)
		)
		(property "dnp" ""
			(at 276.334 -127.868 0)
			(layer "B.Fab")
			(hide yes)
			(effects
				(font
					(size 1 1)
					(thickness 0.15)
				)
				(justify mirror)
			)
		)
		(property "exclude_from_bom" ""
			(at 276.334 -127.868 0)
			(layer "B.Fab")
			(hide yes)
			(effects
				(font
					(size 1 1)
					(thickness 0.15)
				)
				(justify mirror)
			)
		)
		(sheetname "FPGA Config")
		(sheetfile "fpga-config.kicad_sch")
		(attr smd exclude_from_bom)
		(fp_rect
			(start -0.925 0.47)
			(end 0.925 -0.47)
			(stroke
				(width 0.05)
				(type default)
			)
			(fill no)
			(layer "B.CrtYd")
		)
		(fp_rect
			(start -0.5 0.25)
			(end 0.5 -0.25)
			(stroke
				(width 0.15)
				(type solid)
			)
			(fill no)
			(layer "B.Fab")
		)
		(pad "1" smd roundrect
			(at -0.48 0 90)
			(size 0.59 0.64)
			(layers "B.Cu" "B.Mask" "B.Paste")
			(roundrect_rratio 0.25)
			(net 300 "/FPGA Config/MODE0")
			(pintype "passive")
		)
		(pad "2" smd roundrect
			(at 0.48 0 90)
			(size 0.59 0.64)
			(layers "B.Cu" "B.Mask" "B.Paste")
			(roundrect_rratio 0.25)
			(net 24 "+3V3")
			(pintype "passive")
		)
	)
)
